(kicad_pcb
	(version 20260206)
	(generator "pcbnew")
	(generator_version "10.0")
	(general
		(thickness 1.6)
		(legacy_teardrops no)
	)
	(paper "A4")
	(title_block
		(title "01162023_DA0F0TEBIF0_F0T_Expander_BD_F_brd_V02_OCP.brd")
		(comment 1 "Grand Teton / footprint 5622 of 9728 (PEX2), pads 1537-1653 of 2397")
	)
	(layers
		(0 "F.Cu" signal "TOP")
		(4 "In1.Cu" signal "GND")
		(6 "In2.Cu" signal "VCC")
		(8 "In3.Cu" signal "VCC1")
		(10 "In4.Cu" signal "GND1")
		(12 "In5.Cu" signal "IN1")
		(14 "In6.Cu" signal "GND2")
		(16 "In7.Cu" signal "IN2")
		(18 "In8.Cu" signal "GND3")
		(20 "In9.Cu" signal "IN3")
		(22 "In10.Cu" signal "GND4")
		(24 "In11.Cu" signal "IN4")
		(26 "In12.Cu" signal "GND5")
		(28 "In13.Cu" signal "IN5")
		(30 "In14.Cu" signal "GND6")
		(32 "In15.Cu" signal "IN6")
		(34 "In16.Cu" signal "GND7")
		(2 "B.Cu" signal "BOTTOM")
		(9 "F.Adhes" user "F.Adhesive")
		(11 "B.Adhes" user "B.Adhesive")
		(13 "F.Paste" user "Package Geometry/Pastemask Top")
		(15 "B.Paste" user "Package Geometry/Pastemask Bottom")
		(5 "F.SilkS" user "Ref Des/Silkscreen Top")
		(7 "B.SilkS" user "Ref Des/Silkscreen Bottom")
		(1 "F.Mask" user "Board Geometry/Soldermask Top")
		(3 "B.Mask" user "Board Geometry/Soldermask Bottom")
		(17 "Dwgs.User" user "User.Drawings")
		(19 "Cmts.User" user "User.Comments")
		(21 "Eco1.User" user "User.Eco1")
		(23 "Eco2.User" user "User.Eco2")
		(25 "Edge.Cuts" user "Board Geometry/Outline")
		(27 "Margin" user)
		(31 "F.CrtYd" user "Package Geometry/Place Bound Top")
		(29 "B.CrtYd" user "Package Geometry/Place Bound Bottom")
		(35 "F.Fab" user "Ref Des/Assembly Top")
		(33 "B.Fab" user "Ref Des/Assembly Bottom")
	)
	(footprint ""
		(layer "F.Cu")
		(at 291.84981 -295.89984)
		(property "Reference" "PEX2"
			(at -3.35153 35.56762 0)
			(unlocked yes)
			(layer "F.SilkS")
			(effects
				(font
					(size 2.032 1.524)
					(thickness 0.1524)
				)
				(justify left)
			)
		)
		(property "Value" ""
			(at 0 0 0)
			(layer "F.Fab")
			(effects
				(font
					(size 1.27 1.27)
				)
			)
		)
		(duplicate_pad_numbers_are_jumpers no)
		(pad "C22" smd circle
			(at -2.84988 -20.899882)
			(size 0.4572 0.4572)
			(layers "F.Cu" "F.Mask" "F.Paste")
			(net "P5E_PEX2_STN6_RX_DN<97>")
		)
		(pad "C23" smd circle
			(at -1.89992 -20.899882)
			(size 0.4572 0.4572)
			(layers "F.Cu" "F.Mask" "F.Paste")
			(net "GND")
		)
		(pad "C24" smd circle
			(at -0.94996 -20.899882)
			(size 0.4572 0.4572)
			(layers "F.Cu" "F.Mask" "F.Paste")
			(net "P5E_PEX2_STN5_RX_DN<80>")
		)
		(pad "C25" smd circle
			(at 0 -20.899882)
			(size 0.4572 0.4572)
			(layers "F.Cu" "F.Mask" "F.Paste")
			(net "GND")
		)
		(pad "C26" smd circle
			(at 0.94996 -20.899882)
			(size 0.4572 0.4572)
			(layers "F.Cu" "F.Mask" "F.Paste")
			(net "P5E_PEX2_STN5_RX_DN<82>")
		)
		(pad "C27" smd circle
			(at 1.89992 -20.899882)
			(size 0.4572 0.4572)
			(layers "F.Cu" "F.Mask" "F.Paste")
			(net "GND")
		)
		(pad "C28" smd circle
			(at 2.84988 -20.899882)
			(size 0.4572 0.4572)
			(layers "F.Cu" "F.Mask" "F.Paste")
			(net "P5E_PEX2_STN5_RX_DN<84>")
		)
		(pad "C29" smd circle
			(at 3.800094 -20.899882)
			(size 0.4572 0.4572)
			(layers "F.Cu" "F.Mask" "F.Paste")
			(net "GND")
		)
		(pad "C30" smd circle
			(at 4.750054 -20.899882)
			(size 0.4572 0.4572)
			(layers "F.Cu" "F.Mask" "F.Paste")
			(net "P5E_PEX2_STN5_RX_DN<86>")
		)
		(pad "C31" smd circle
			(at 5.700014 -20.899882)
			(size 0.4572 0.4572)
			(layers "F.Cu" "F.Mask" "F.Paste")
			(net "GND")
		)
		(pad "C32" smd circle
			(at 6.649974 -20.899882)
			(size 0.4572 0.4572)
			(layers "F.Cu" "F.Mask" "F.Paste")
			(net "P5E_PEX2_STN5_RX_DN<88>")
		)
		(pad "C33" smd circle
			(at 7.599934 -20.899882)
			(size 0.4572 0.4572)
			(layers "F.Cu" "F.Mask" "F.Paste")
			(net "GND")
		)
		(pad "C34" smd circle
			(at 8.549894 -20.899882)
			(size 0.4572 0.4572)
			(layers "F.Cu" "F.Mask" "F.Paste")
			(net "P5E_PEX2_STN5_RX_DN<90>")
		)
		(pad "C35" smd circle
			(at 9.500108 -20.899882)
			(size 0.4572 0.4572)
			(layers "F.Cu" "F.Mask" "F.Paste")
			(net "GND")
		)
		(pad "C36" smd circle
			(at 10.450068 -20.899882)
			(size 0.4572 0.4572)
			(layers "F.Cu" "F.Mask" "F.Paste")
			(net "P5E_PEX2_STN5_RX_DN<92>")
		)
		(pad "C37" smd circle
			(at 11.400028 -20.899882)
			(size 0.4572 0.4572)
			(layers "F.Cu" "F.Mask" "F.Paste")
			(net "GND")
		)
		(pad "C38" smd circle
			(at 12.349988 -20.899882)
			(size 0.4572 0.4572)
			(layers "F.Cu" "F.Mask" "F.Paste")
			(net "P5E_PEX2_STN5_RX_DN<94>")
		)
		(pad "C39" smd circle
			(at 13.299948 -20.899882)
			(size 0.4572 0.4572)
			(layers "F.Cu" "F.Mask" "F.Paste")
			(net "GND")
		)
		(pad "C40" smd circle
			(at 14.249908 -20.899882)
			(size 0.4572 0.4572)
			(layers "F.Cu" "F.Mask" "F.Paste")
			(net "P5E_PEX2_STN4_RX_DN<79>")
		)
		(pad "C41" smd circle
			(at 15.200122 -20.899882)
			(size 0.4572 0.4572)
			(layers "F.Cu" "F.Mask" "F.Paste")
			(net "GND")
		)
		(pad "C42" smd circle
			(at 16.150082 -20.899882)
			(size 0.4572 0.4572)
			(layers "F.Cu" "F.Mask" "F.Paste")
			(net "P5E_PEX2_STN4_RX_DN<77>")
		)
		(pad "C43" smd circle
			(at 17.100042 -20.899882)
			(size 0.4572 0.4572)
			(layers "F.Cu" "F.Mask" "F.Paste")
			(net "GND")
		)
		(pad "C44" smd circle
			(at 18.050002 -20.899882)
			(size 0.4572 0.4572)
			(layers "F.Cu" "F.Mask" "F.Paste")
			(net "P5E_PEX2_STN4_RX_DN<75>")
		)
		(pad "C45" smd circle
			(at 18.999962 -20.899882)
			(size 0.4572 0.4572)
			(layers "F.Cu" "F.Mask" "F.Paste")
			(net "GND")
		)
		(pad "C46" smd circle
			(at 19.949922 -20.899882)
			(size 0.4572 0.4572)
			(layers "F.Cu" "F.Mask" "F.Paste")
			(net "P5E_PEX2_STN4_RX_DN<73>")
		)
		(pad "C47" smd circle
			(at 20.899882 -20.899882)
			(size 0.4572 0.4572)
			(layers "F.Cu" "F.Mask" "F.Paste")
			(net "GND")
		)
		(pad "C48" smd circle
			(at 21.850096 -20.899882)
			(size 0.4572 0.4572)
			(layers "F.Cu" "F.Mask" "F.Paste")
			(net "P5E_PEX2_STN4_RX_DP<71>")
		)
		(pad "C49" smd circle
			(at 22.800056 -20.899882)
			(size 0.4572 0.4572)
			(layers "F.Cu" "F.Mask" "F.Paste")
			(net "P5E_PEX2_STN4_RX_DN<71>")
		)
		(pad "D1" smd circle
			(at -22.800056 -19.949922)
			(size 0.4572 0.4572)
			(layers "F.Cu" "F.Mask" "F.Paste")
			(net "GND")
		)
		(pad "D2" smd circle
			(at -21.850096 -19.949922)
			(size 0.4572 0.4572)
			(layers "F.Cu" "F.Mask" "F.Paste")
			(net "GND")
		)
		(pad "D3" smd circle
			(at -20.899882 -19.949922)
			(size 0.4572 0.4572)
			(layers "F.Cu" "F.Mask" "F.Paste")
			(net "GND")
		)
		(pad "D4" smd circle
			(at -19.949922 -19.949922)
			(size 0.4572 0.4572)
			(layers "F.Cu" "F.Mask" "F.Paste")
			(net "P5E_PEX2_STN7_RX_DP<124>")
		)
		(pad "D5" smd circle
			(at -18.999962 -19.949922)
			(size 0.4572 0.4572)
			(layers "F.Cu" "F.Mask" "F.Paste")
			(net "GND")
		)
		(pad "D6" smd circle
			(at -18.050002 -19.949922)
			(size 0.4572 0.4572)
			(layers "F.Cu" "F.Mask" "F.Paste")
			(net "P5E_PEX2_STN7_RX_DP<126>")
		)
		(pad "D7" smd circle
			(at -17.100042 -19.949922)
			(size 0.4572 0.4572)
			(layers "F.Cu" "F.Mask" "F.Paste")
			(net "GND")
		)
		(pad "D8" smd circle
			(at -16.150082 -19.949922)
			(size 0.4572 0.4572)
			(layers "F.Cu" "F.Mask" "F.Paste")
			(net "P5E_PEX2_STN6_RX_DP<111>")
		)
		(pad "D9" smd circle
			(at -15.200122 -19.949922)
			(size 0.4572 0.4572)
			(layers "F.Cu" "F.Mask" "F.Paste")
			(net "GND")
		)
		(pad "D10" smd circle
			(at -14.249908 -19.949922)
			(size 0.4572 0.4572)
			(layers "F.Cu" "F.Mask" "F.Paste")
			(net "P5E_PEX2_STN6_RX_DP<109>")
		)
		(pad "D11" smd circle
			(at -13.299948 -19.949922)
			(size 0.4572 0.4572)
			(layers "F.Cu" "F.Mask" "F.Paste")
			(net "GND")
		)
		(pad "D12" smd circle
			(at -12.349988 -19.949922)
			(size 0.4572 0.4572)
			(layers "F.Cu" "F.Mask" "F.Paste")
			(net "P5E_PEX2_STN6_RX_DP<107>")
		)
		(pad "D13" smd circle
			(at -11.400028 -19.949922)
			(size 0.4572 0.4572)
			(layers "F.Cu" "F.Mask" "F.Paste")
			(net "GND")
		)
		(pad "D14" smd circle
			(at -10.450068 -19.949922)
			(size 0.4572 0.4572)
			(layers "F.Cu" "F.Mask" "F.Paste")
			(net "P5E_PEX2_STN6_RX_DP<105>")
		)
		(pad "D15" smd circle
			(at -9.500108 -19.949922)
			(size 0.4572 0.4572)
			(layers "F.Cu" "F.Mask" "F.Paste")
			(net "GND")
		)
		(pad "D16" smd circle
			(at -8.549894 -19.949922)
			(size 0.4572 0.4572)
			(layers "F.Cu" "F.Mask" "F.Paste")
			(net "P5E_PEX2_STN6_RX_DP<103>")
		)
		(pad "D17" smd circle
			(at -7.599934 -19.949922)
			(size 0.4572 0.4572)
			(layers "F.Cu" "F.Mask" "F.Paste")
			(net "GND")
		)
		(pad "D18" smd circle
			(at -6.649974 -19.949922)
			(size 0.4572 0.4572)
			(layers "F.Cu" "F.Mask" "F.Paste")
			(net "P5E_PEX2_STN6_RX_DP<101>")
		)
		(pad "D19" smd circle
			(at -5.700014 -19.949922)
			(size 0.4572 0.4572)
			(layers "F.Cu" "F.Mask" "F.Paste")
			(net "GND")
		)
		(pad "D20" smd circle
			(at -4.750054 -19.949922)
			(size 0.4572 0.4572)
			(layers "F.Cu" "F.Mask" "F.Paste")
			(net "P5E_PEX2_STN6_RX_DP<99>")
		)
		(pad "D21" smd circle
			(at -3.800094 -19.949922)
			(size 0.4572 0.4572)
			(layers "F.Cu" "F.Mask" "F.Paste")
			(net "GND")
		)
		(pad "D22" smd circle
			(at -2.84988 -19.949922)
			(size 0.4572 0.4572)
			(layers "F.Cu" "F.Mask" "F.Paste")
			(net "P5E_PEX2_STN6_RX_DP<97>")
		)
		(pad "D23" smd circle
			(at -1.89992 -19.949922)
			(size 0.4572 0.4572)
			(layers "F.Cu" "F.Mask" "F.Paste")
			(net "GND")
		)
		(pad "D24" smd circle
			(at -0.94996 -19.949922)
			(size 0.4572 0.4572)
			(layers "F.Cu" "F.Mask" "F.Paste")
			(net "P5E_PEX2_STN5_RX_DP<80>")
		)
		(pad "D25" smd circle
			(at 0 -19.949922)
			(size 0.4572 0.4572)
			(layers "F.Cu" "F.Mask" "F.Paste")
			(net "GND")
		)
		(pad "D26" smd circle
			(at 0.94996 -19.949922)
			(size 0.4572 0.4572)
			(layers "F.Cu" "F.Mask" "F.Paste")
			(net "P5E_PEX2_STN5_RX_DP<82>")
		)
		(pad "D27" smd circle
			(at 1.89992 -19.949922)
			(size 0.4572 0.4572)
			(layers "F.Cu" "F.Mask" "F.Paste")
			(net "GND")
		)
		(pad "D28" smd circle
			(at 2.84988 -19.949922)
			(size 0.4572 0.4572)
			(layers "F.Cu" "F.Mask" "F.Paste")
			(net "P5E_PEX2_STN5_RX_DP<84>")
		)
		(pad "D29" smd circle
			(at 3.800094 -19.949922)
			(size 0.4572 0.4572)
			(layers "F.Cu" "F.Mask" "F.Paste")
			(net "GND")
		)
		(pad "D30" smd circle
			(at 4.750054 -19.949922)
			(size 0.4572 0.4572)
			(layers "F.Cu" "F.Mask" "F.Paste")
			(net "P5E_PEX2_STN5_RX_DP<86>")
		)
		(pad "D31" smd circle
			(at 5.700014 -19.949922)
			(size 0.4572 0.4572)
			(layers "F.Cu" "F.Mask" "F.Paste")
			(net "GND")
		)
		(pad "D32" smd circle
			(at 6.649974 -19.949922)
			(size 0.4572 0.4572)
			(layers "F.Cu" "F.Mask" "F.Paste")
			(net "P5E_PEX2_STN5_RX_DP<88>")
		)
		(pad "D33" smd circle
			(at 7.599934 -19.949922)
			(size 0.4572 0.4572)
			(layers "F.Cu" "F.Mask" "F.Paste")
			(net "GND")
		)
		(pad "D34" smd circle
			(at 8.549894 -19.949922)
			(size 0.4572 0.4572)
			(layers "F.Cu" "F.Mask" "F.Paste")
			(net "P5E_PEX2_STN5_RX_DP<90>")
		)
		(pad "D35" smd circle
			(at 9.500108 -19.949922)
			(size 0.4572 0.4572)
			(layers "F.Cu" "F.Mask" "F.Paste")
			(net "GND")
		)
		(pad "D36" smd circle
			(at 10.450068 -19.949922)
			(size 0.4572 0.4572)
			(layers "F.Cu" "F.Mask" "F.Paste")
			(net "P5E_PEX2_STN5_RX_DP<92>")
		)
		(pad "D37" smd circle
			(at 11.400028 -19.949922)
			(size 0.4572 0.4572)
			(layers "F.Cu" "F.Mask" "F.Paste")
			(net "GND")
		)
		(pad "D38" smd circle
			(at 12.349988 -19.949922)
			(size 0.4572 0.4572)
			(layers "F.Cu" "F.Mask" "F.Paste")
			(net "P5E_PEX2_STN5_RX_DP<94>")
		)
		(pad "D39" smd circle
			(at 13.299948 -19.949922)
			(size 0.4572 0.4572)
			(layers "F.Cu" "F.Mask" "F.Paste")
			(net "GND")
		)
		(pad "D40" smd circle
			(at 14.249908 -19.949922)
			(size 0.4572 0.4572)
			(layers "F.Cu" "F.Mask" "F.Paste")
			(net "P5E_PEX2_STN4_RX_DP<79>")
		)
		(pad "D41" smd circle
			(at 15.200122 -19.949922)
			(size 0.4572 0.4572)
			(layers "F.Cu" "F.Mask" "F.Paste")
			(net "GND")
		)
		(pad "D42" smd circle
			(at 16.150082 -19.949922)
			(size 0.4572 0.4572)
			(layers "F.Cu" "F.Mask" "F.Paste")
			(net "P5E_PEX2_STN4_RX_DP<77>")
		)
		(pad "D43" smd circle
			(at 17.100042 -19.949922)
			(size 0.4572 0.4572)
			(layers "F.Cu" "F.Mask" "F.Paste")
			(net "GND")
		)
		(pad "D44" smd circle
			(at 18.050002 -19.949922)
			(size 0.4572 0.4572)
			(layers "F.Cu" "F.Mask" "F.Paste")
			(net "P5E_PEX2_STN4_RX_DP<75>")
		)
		(pad "D45" smd circle
			(at 18.999962 -19.949922)
			(size 0.4572 0.4572)
			(layers "F.Cu" "F.Mask" "F.Paste")
			(net "GND")
		)
		(pad "D46" smd circle
			(at 19.949922 -19.949922)
			(size 0.4572 0.4572)
			(layers "F.Cu" "F.Mask" "F.Paste")
			(net "P5E_PEX2_STN4_RX_DP<73>")
		)
		(pad "D47" smd circle
			(at 20.899882 -19.949922)
			(size 0.4572 0.4572)
			(layers "F.Cu" "F.Mask" "F.Paste")
			(net "GND")
		)
		(pad "D48" smd circle
			(at 21.850096 -19.949922)
			(size 0.4572 0.4572)
			(layers "F.Cu" "F.Mask" "F.Paste")
			(net "GND")
		)
		(pad "D49" smd circle
			(at 22.800056 -19.949922)
			(size 0.4572 0.4572)
			(layers "F.Cu" "F.Mask" "F.Paste")
			(net "GND")
		)
		(pad "E1" smd circle
			(at -22.800056 -18.999962)
			(size 0.4572 0.4572)
			(layers "F.Cu" "F.Mask" "F.Paste")
			(net "P5E_PEX2_STN7_TX_DN<122>")
		)
		(pad "E2" smd circle
			(at -21.850096 -18.999962)
			(size 0.4572 0.4572)
			(layers "F.Cu" "F.Mask" "F.Paste")
			(net "P5E_PEX2_STN7_TX_DP<122>")
		)
		(pad "E3" smd circle
			(at -20.899882 -18.999962)
			(size 0.4572 0.4572)
			(layers "F.Cu" "F.Mask" "F.Paste")
			(net "GND")
		)
		(pad "E4" smd circle
			(at -19.949922 -18.999962)
			(size 0.4572 0.4572)
			(layers "F.Cu" "F.Mask" "F.Paste")
			(net "GND")
		)
		(pad "E5" smd circle
			(at -18.999962 -18.999962)
			(size 0.4572 0.4572)
			(layers "F.Cu" "F.Mask" "F.Paste")
			(net "GND")
		)
		(pad "E6" smd circle
			(at -18.050002 -18.999962)
			(size 0.4572 0.4572)
			(layers "F.Cu" "F.Mask" "F.Paste")
			(net "GND")
		)
		(pad "E7" smd circle
			(at -17.100042 -18.999962)
			(size 0.4572 0.4572)
			(layers "F.Cu" "F.Mask" "F.Paste")
			(net "GND")
		)
		(pad "E8" smd circle
			(at -16.150082 -18.999962)
			(size 0.4572 0.4572)
			(layers "F.Cu" "F.Mask" "F.Paste")
			(net "GND")
		)
		(pad "E9" smd circle
			(at -15.200122 -18.999962)
			(size 0.4572 0.4572)
			(layers "F.Cu" "F.Mask" "F.Paste")
			(net "GND")
		)
		(pad "E10" smd circle
			(at -14.249908 -18.999962)
			(size 0.4572 0.4572)
			(layers "F.Cu" "F.Mask" "F.Paste")
			(net "GND")
		)
		(pad "E11" smd circle
			(at -13.299948 -18.999962)
			(size 0.4572 0.4572)
			(layers "F.Cu" "F.Mask" "F.Paste")
			(net "GND")
		)
		(pad "E12" smd circle
			(at -12.349988 -18.999962)
			(size 0.4572 0.4572)
			(layers "F.Cu" "F.Mask" "F.Paste")
			(net "GND")
		)
		(pad "E13" smd circle
			(at -11.400028 -18.999962)
			(size 0.4572 0.4572)
			(layers "F.Cu" "F.Mask" "F.Paste")
			(net "GND")
		)
		(pad "E14" smd circle
			(at -10.450068 -18.999962)
			(size 0.4572 0.4572)
			(layers "F.Cu" "F.Mask" "F.Paste")
			(net "GND")
		)
		(pad "E15" smd circle
			(at -9.500108 -18.999962)
			(size 0.4572 0.4572)
			(layers "F.Cu" "F.Mask" "F.Paste")
			(net "GND")
		)
		(pad "E16" smd circle
			(at -8.549894 -18.999962)
			(size 0.4572 0.4572)
			(layers "F.Cu" "F.Mask" "F.Paste")
			(net "GND")
		)
		(pad "E17" smd circle
			(at -7.599934 -18.999962)
			(size 0.4572 0.4572)
			(layers "F.Cu" "F.Mask" "F.Paste")
			(net "GND")
		)
		(pad "E18" smd circle
			(at -6.649974 -18.999962)
			(size 0.4572 0.4572)
			(layers "F.Cu" "F.Mask" "F.Paste")
			(net "GND")
		)
		(pad "E19" smd circle
			(at -5.700014 -18.999962)
			(size 0.4572 0.4572)
			(layers "F.Cu" "F.Mask" "F.Paste")
			(net "GND")
		)
		(pad "E20" smd circle
			(at -4.750054 -18.999962)
			(size 0.4572 0.4572)
			(layers "F.Cu" "F.Mask" "F.Paste")
			(net "GND")
		)
		(pad "E21" smd circle
			(at -3.800094 -18.999962)
			(size 0.4572 0.4572)
			(layers "F.Cu" "F.Mask" "F.Paste")
			(net "GND")
		)
		(pad "E22" smd circle
			(at -2.84988 -18.999962)
			(size 0.4572 0.4572)
			(layers "F.Cu" "F.Mask" "F.Paste")
			(net "GND")
		)
		(pad "E23" smd circle
			(at -1.89992 -18.999962)
			(size 0.4572 0.4572)
			(layers "F.Cu" "F.Mask" "F.Paste")
			(net "GND")
		)
		(pad "E24" smd circle
			(at -0.94996 -18.999962)
			(size 0.4572 0.4572)
			(layers "F.Cu" "F.Mask" "F.Paste")
			(net "GND")
		)
		(pad "E25" smd circle
			(at 0 -18.999962)
			(size 0.4572 0.4572)
			(layers "F.Cu" "F.Mask" "F.Paste")
			(net "GND")
		)
		(pad "E26" smd circle
			(at 0.94996 -18.999962)
			(size 0.4572 0.4572)
			(layers "F.Cu" "F.Mask" "F.Paste")
			(net "GND")
		)
		(pad "E27" smd circle
			(at 1.89992 -18.999962)
			(size 0.4572 0.4572)
			(layers "F.Cu" "F.Mask" "F.Paste")
			(net "GND")
		)
		(pad "E28" smd circle
			(at 2.84988 -18.999962)
			(size 0.4572 0.4572)
			(layers "F.Cu" "F.Mask" "F.Paste")
			(net "GND")
		)
		(pad "E29" smd circle
			(at 3.800094 -18.999962)
			(size 0.4572 0.4572)
			(layers "F.Cu" "F.Mask" "F.Paste")
			(net "GND")
		)
		(pad "E30" smd circle
			(at 4.750054 -18.999962)
			(size 0.4572 0.4572)
			(layers "F.Cu" "F.Mask" "F.Paste")
			(net "GND")
		)
		(pad "E31" smd circle
			(at 5.700014 -18.999962)
			(size 0.4572 0.4572)
			(layers "F.Cu" "F.Mask" "F.Paste")
			(net "GND")
		)
		(pad "E32" smd circle
			(at 6.649974 -18.999962)
			(size 0.4572 0.4572)
			(layers "F.Cu" "F.Mask" "F.Paste")
			(net "GND")
		)
		(pad "E33" smd circle
			(at 7.599934 -18.999962)
			(size 0.4572 0.4572)
			(layers "F.Cu" "F.Mask" "F.Paste")
			(net "GND")
		)
		(pad "E34" smd circle
			(at 8.549894 -18.999962)
			(size 0.4572 0.4572)
			(layers "F.Cu" "F.Mask" "F.Paste")
			(net "GND")
		)
		(pad "E35" smd circle
			(at 9.500108 -18.999962)
			(size 0.4572 0.4572)
			(layers "F.Cu" "F.Mask" "F.Paste")
			(net "GND")
		)
		(pad "E36" smd circle
			(at 10.450068 -18.999962)
			(size 0.4572 0.4572)
			(layers "F.Cu" "F.Mask" "F.Paste")
			(net "GND")
		)
		(pad "E37" smd circle
			(at 11.400028 -18.999962)
			(size 0.4572 0.4572)
			(layers "F.Cu" "F.Mask" "F.Paste")
			(net "GND")
		)
		(pad "E38" smd circle
			(at 12.349988 -18.999962)
			(size 0.4572 0.4572)
			(layers "F.Cu" "F.Mask" "F.Paste")
			(net "GND")
		)
		(pad "E39" smd circle
			(at 13.299948 -18.999962)
			(size 0.4572 0.4572)
			(layers "F.Cu" "F.Mask" "F.Paste")
			(net "GND")
		)
		(pad "E40" smd circle
			(at 14.249908 -18.999962)
			(size 0.4572 0.4572)
			(layers "F.Cu" "F.Mask" "F.Paste")
			(net "GND")
		)
	)
)
